#ISCELL
  logical_power cad_note *
  *
#ISCELL
  pure_quanta quanta_title_block_c *
  *
#ISCELL
  standard offpage *
  page112_i1
#ISCELL
  standard offpage *
  page112_i10
#ISCELL
  standard tap *
  page112_i100
#ISCELL
  standard offpage *
  page112_i101
#ISCELL
  standard tap *
  page112_i102
#ISCELL
  standard tap *
  page112_i103
#ISCELL
  standard tap *
  page112_i104
#ISCELL
  standard tap *
  page112_i105
#ISCELL
  standard tap *
  page112_i106
#ISCELL
  standard tap *
  page112_i107
#ISCELL
  standard tap *
  page112_i108
#ISCELL
  standard tap *
  page112_i109
#ISCELL
  standard offpage *
  page112_i11
#ISCELL
  standard tap *
  page112_i110
#ISCELL
  standard tap *
  page112_i111
#ISCELL
  standard tap *
  page112_i112
#ISCELL
  standard tap *
  page112_i113
#ISCELL
  standard tap *
  page112_i114
#ISCELL
  standard tap *
  page112_i115
#ISCELL
  standard tap *
  page112_i116
#ISCELL
  standard tap *
  page112_i117
#ISCELL
  standard tap *
  page112_i118
#ISCELL
  standard tap *
  page112_i119
#ISCELL
  logical_power vcc_core *
  page112_i12
#ISCELL
  standard tap *
  page112_i120
#ISCELL
  standard offpage *
  page112_i121
#ISCELL
  logical_power universal_gnd *
  page112_i122
#ISCELL
  logical_power universal_gnd *
  page112_i123
#CELL
  pure_quanta q_cap *
  page112_i124
#CELL
  pure_quanta q_cap *
  page112_i125
#CELL
  pure_quanta q_cap *
  page112_i126
#ISCELL
  logical_power vcc_core *
  page112_i127
#ISCELL
  logical_power vcc_core *
  page112_i129
#ISCELL
  standard tap *
  page112_i130
#ISCELL
  standard tap *
  page112_i131
#ISCELL
  standard tap *
  page112_i132
#ISCELL
  standard tap *
  page112_i133
#ISCELL
  standard tap *
  page112_i134
#ISCELL
  standard tap *
  page112_i135
#ISCELL
  standard tap *
  page112_i136
#ISCELL
  standard tap *
  page112_i137
#ISCELL
  standard tap *
  page112_i138
#ISCELL
  standard tap *
  page112_i139
#ISCELL
  standard tap *
  page112_i14
#ISCELL
  standard tap *
  page112_i140
#ISCELL
  standard tap *
  page112_i141
#ISCELL
  standard tap *
  page112_i142
#ISCELL
  standard tap *
  page112_i143
#ISCELL
  standard tap *
  page112_i144
#ISCELL
  standard tap *
  page112_i145
#ISCELL
  standard tap *
  page112_i146
#ISCELL
  standard tap *
  page112_i147
#ISCELL
  standard tap *
  page112_i148
#ISCELL
  standard tap *
  page112_i149
#ISCELL
  standard tap *
  page112_i15
#ISCELL
  standard tap *
  page112_i150
#ISCELL
  standard tap *
  page112_i151
#ISCELL
  standard tap *
  page112_i152
#ISCELL
  standard tap *
  page112_i153
#ISCELL
  standard tap *
  page112_i154
#ISCELL
  standard tap *
  page112_i155
#ISCELL
  standard tap *
  page112_i156
#ISCELL
  standard tap *
  page112_i157
#ISCELL
  standard tap *
  page112_i158
#ISCELL
  standard tap *
  page112_i159
#ISCELL
  standard tap *
  page112_i16
#ISCELL
  standard tap *
  page112_i160
#ISCELL
  standard tap *
  page112_i161
#ISCELL
  standard tap *
  page112_i162
#ISCELL
  standard tap *
  page112_i163
#ISCELL
  standard tap *
  page112_i164
#ISCELL
  standard tap *
  page112_i165
#ISCELL
  standard tap *
  page112_i166
#ISCELL
  standard tap *
  page112_i167
#ISCELL
  standard tap *
  page112_i168
#ISCELL
  standard tap *
  page112_i169
#ISCELL
  standard tap *
  page112_i17
#ISCELL
  logical_power universal_gnd *
  page112_i170
#ISCELL
  standard offpage *
  page112_i172
#ISCELL
  standard offpage *
  page112_i173
#ISCELL
  standard offpage *
  page112_i174
#ISCELL
  standard offpage *
  page112_i175
#ISCELL
  logical_power vcc_core *
  page112_i176
#ISCELL
  logical_power universal_gnd *
  page112_i177
#CELL
  pure_quanta sconn288_adr50017p130cc *
  page112_i178
#ISCELL
  standard tap *
  page112_i18
#CELL
  pure_quanta sconn288_adr50017p130cc *
  page112_i180
#CELL
  pure_quanta sconn288_adr50017p130cc *
  page112_i181
#ISCELL
  standard offpage *
  page112_i182
#CELL
  pure_quanta q_res *
  page112_i183
#ISCELL
  standard tap *
  page112_i19
#ISCELL
  logical_power universal_gnd *
  page112_i2
#ISCELL
  standard offpage *
  page112_i20
#ISCELL
  standard offpage *
  page112_i21
#ISCELL
  standard offpage *
  page112_i22
#ISCELL
  standard offpage *
  page112_i23
#ISCELL
  standard offpage *
  page112_i24
#ISCELL
  standard offpage *
  page112_i25
#ISCELL
  standard offpage *
  page112_i26
#ISCELL
  standard offpage *
  page112_i27
#ISCELL
  standard offpage *
  page112_i28
#ISCELL
  standard offpage *
  page112_i29
#CELL
  pure_quanta q_res *
  page112_i3
#ISCELL
  standard offpage *
  page112_i30
#ISCELL
  standard offpage *
  page112_i31
#ISCELL
  standard tap *
  page112_i32
#ISCELL
  standard tap *
  page112_i33
#ISCELL
  standard tap *
  page112_i34
#ISCELL
  standard tap *
  page112_i35
#ISCELL
  standard tap *
  page112_i36
#ISCELL
  standard tap *
  page112_i37
#ISCELL
  standard tap *
  page112_i38
#ISCELL
  standard tap *
  page112_i39
#ISCELL
  standard offpage *
  page112_i4
#ISCELL
  standard tap *
  page112_i40
#ISCELL
  standard tap *
  page112_i41
#ISCELL
  standard tap *
  page112_i42
#ISCELL
  standard tap *
  page112_i43
#ISCELL
  standard tap *
  page112_i44
#ISCELL
  standard tap *
  page112_i45
#ISCELL
  standard tap *
  page112_i46
#ISCELL
  standard tap *
  page112_i47
#ISCELL
  standard tap *
  page112_i48
#ISCELL
  standard tap *
  page112_i49
#ISCELL
  standard offpage *
  page112_i5
#ISCELL
  standard tap *
  page112_i50
#ISCELL
  standard tap *
  page112_i51
#ISCELL
  standard tap *
  page112_i52
#ISCELL
  standard tap *
  page112_i53
#ISCELL
  standard tap *
  page112_i54
#ISCELL
  standard tap *
  page112_i55
#ISCELL
  standard tap *
  page112_i56
#ISCELL
  standard tap *
  page112_i57
#ISCELL
  standard tap *
  page112_i58
#ISCELL
  standard tap *
  page112_i59
#ISCELL
  standard offpage *
  page112_i6
#ISCELL
  standard tap *
  page112_i60
#ISCELL
  standard tap *
  page112_i61
#ISCELL
  standard tap *
  page112_i62
#ISCELL
  standard tap *
  page112_i63
#ISCELL
  standard tap *
  page112_i64
#ISCELL
  standard tap *
  page112_i65
#ISCELL
  standard tap *
  page112_i66
#ISCELL
  standard tap *
  page112_i67
#ISCELL
  standard tap *
  page112_i68
#ISCELL
  standard tap *
  page112_i69
#ISCELL
  standard tap *
  page112_i70
#ISCELL
  standard tap *
  page112_i71
#ISCELL
  standard tap *
  page112_i72
#ISCELL
  standard tap *
  page112_i73
#ISCELL
  standard tap *
  page112_i74
#ISCELL
  standard tap *
  page112_i75
#ISCELL
  standard tap *
  page112_i76
#ISCELL
  standard tap *
  page112_i77
#ISCELL
  standard tap *
  page112_i78
#ISCELL
  standard tap *
  page112_i79
#ISCELL
  standard offpage *
  page112_i8
#ISCELL
  standard tap *
  page112_i80
#ISCELL
  standard tap *
  page112_i81
#ISCELL
  standard tap *
  page112_i82
#ISCELL
  standard tap *
  page112_i83
#ISCELL
  standard tap *
  page112_i84
#ISCELL
  standard tap *
  page112_i85
#ISCELL
  standard tap *
  page112_i86
#ISCELL
  standard tap *
  page112_i87
#ISCELL
  standard tap *
  page112_i88
#ISCELL
  standard tap *
  page112_i89
#ISCELL
  standard offpage *
  page112_i9
#ISCELL
  standard tap *
  page112_i90
#ISCELL
  standard tap *
  page112_i91
#ISCELL
  standard tap *
  page112_i92
#ISCELL
  standard tap *
  page112_i93
#ISCELL
  standard tap *
  page112_i94
#ISCELL
  standard tap *
  page112_i95
#ISCELL
  standard tap *
  page112_i96
#ISCELL
  standard tap *
  page112_i97
#ISCELL
  standard tap *
  page112_i98
#ISCELL
  standard tap *
  page112_i99
